# T6G (Grand Teton) — schematic netlist excerpt (pin names and nets, part order shuffled) for the footprints in the layout excerpt that follows; sources: Cadence DE-HDL packaged netlist, KiCad conversion of 04192023_DAF0TMB3IC0_F0TG_MB_C_brd_V02_OCP.brd

R4067  Q_RES  10K 1% CHIP  pkg 0402LF  page 140 : A = P12V_AUX ; B = P3V3_OCP_2_EN_G

(kicad_pcb
	(version 20260206)
	(generator "pcbnew")
	(generator_version "10.0")
	(general
		(thickness 1.6)
		(legacy_teardrops no)
	)
	(paper "A4")
	(title_block
		(title "04192023_DAF0TMB3IC0_F0TG_MB_C_brd_V02_OCP.brd")
		(comment 1 "Grand Teton / footprints 3167-3168 of 8354")
	)
	(layers
		(0 "F.Cu" signal "TOP")
		(4 "In1.Cu" signal "GND")
		(6 "In2.Cu" signal "IN1")
		(8 "In3.Cu" signal "GND1")
		(10 "In4.Cu" signal "IN2")
		(12 "In5.Cu" signal "GND2")
		(14 "In6.Cu" signal "IN3")
		(16 "In7.Cu" signal "GND3")
		(18 "In8.Cu" signal "VCC")
		(20 "In9.Cu" signal "VCC1")
		(22 "In10.Cu" signal "GND4")
		(24 "In11.Cu" signal "IN4")
		(26 "In12.Cu" signal "GND5")
		(28 "In13.Cu" signal "IN5")
		(30 "In14.Cu" signal "GND6")
		(32 "In15.Cu" signal "IN6")
		(34 "In16.Cu" signal "GND7")
		(2 "B.Cu" signal "BOTTOM")
		(9 "F.Adhes" user "F.Adhesive")
		(11 "B.Adhes" user "B.Adhesive")
		(13 "F.Paste" user "Package Geometry/Pastemask Top")
		(15 "B.Paste" user "Package Geometry/Pastemask Bottom")
		(5 "F.SilkS" user "Ref Des/Silkscreen Top")
		(7 "B.SilkS" user "Ref Des/Silkscreen Bottom")
		(1 "F.Mask" user "Board Geometry/Soldermask Top")
		(3 "B.Mask" user "Board Geometry/Soldermask Bottom")
		(17 "Dwgs.User" user "User.Drawings")
		(19 "Cmts.User" user "User.Comments")
		(21 "Eco1.User" user "User.Eco1")
		(23 "Eco2.User" user "User.Eco2")
		(25 "Edge.Cuts" user "Board Geometry/Outline")
		(27 "Margin" user)
		(31 "F.CrtYd" user "Package Geometry/Place Bound Top")
		(29 "B.CrtYd" user "Package Geometry/Place Bound Bottom")
		(35 "F.Fab" user "Ref Des/Assembly Top")
		(33 "B.Fab" user "Ref Des/Assembly Bottom")
	)
	(footprint ""
		(layer "F.Cu")
		(at 64.708024 -40.208708 90)
		(property "Reference" "R4067"
			(at 0 0 90)
			(layer "F.SilkS")
			(hide yes)
			(effects
				(font
					(size 1.27 1.27)
				)
			)
		)
		(property "Value" ""
			(at 0 0 90)
			(layer "F.Fab")
			(effects
				(font
					(size 1.27 1.27)
				)
			)
		)
		(duplicate_pad_numbers_are_jumpers no)
		(fp_line
			(start 0.7874 -0.4064)
			(end 0.7874 0.4064)
			(stroke
				(width 0.1524)
				(type default)
			)
			(layer "F.SilkS")
		)
		(fp_line
			(start -0.7874 -0.4064)
			(end 0.7874 -0.4064)
			(stroke
				(width 0.1524)
				(type default)
			)
			(layer "F.SilkS")
		)
		(fp_line
			(start 0.7874 0.4064)
			(end -0.7874 0.4064)
			(stroke
				(width 0.1524)
				(type default)
			)
			(layer "F.SilkS")
		)
		(fp_line
			(start -0.7874 0.4064)
			(end -0.7874 -0.4064)
			(stroke
				(width 0.1524)
				(type default)
			)
			(layer "F.SilkS")
		)
		(fp_line
			(start -0.12065 -0.305054)
			(end -0.12065 -0.2794)
			(stroke
				(width 0.1)
				(type default)
			)
			(layer "F.Fab")
		)
		(fp_line
			(start -0.67945 -0.305054)
			(end -0.12065 -0.305054)
			(stroke
				(width 0.1)
				(type default)
			)
			(layer "F.Fab")
		)
		(fp_line
			(start 0.67945 -0.3048)
			(end 0.67945 0.3048)
			(stroke
				(width 0.1)
				(type default)
			)
			(layer "F.Fab")
		)
		(fp_line
			(start 0.12065 -0.3048)
			(end 0.67945 -0.3048)
			(stroke
				(width 0.1)
				(type default)
			)
			(layer "F.Fab")
		)
		(fp_line
			(start 0.12065 -0.2794)
			(end 0.12065 -0.3048)
			(stroke
				(width 0.1)
				(type default)
			)
			(layer "F.Fab")
		)
		(fp_line
			(start -0.12065 -0.2794)
			(end 0.12065 -0.2794)
			(stroke
				(width 0.1)
				(type default)
			)
			(layer "F.Fab")
		)
		(fp_line
			(start 0.120396 0.2794)
			(end -0.12065 0.2794)
			(stroke
				(width 0.1)
				(type default)
			)
			(layer "F.Fab")
		)
		(fp_line
			(start -0.12065 0.2794)
			(end -0.12065 0.3048)
			(stroke
				(width 0.1)
				(type default)
			)
			(layer "F.Fab")
		)
		(fp_line
			(start 0.67945 0.3048)
			(end 0.120396 0.3048)
			(stroke
				(width 0.1)
				(type default)
			)
			(layer "F.Fab")
		)
		(fp_line
			(start 0.120396 0.3048)
			(end 0.120396 0.2794)
			(stroke
				(width 0.1)
				(type default)
			)
			(layer "F.Fab")
		)
		(fp_line
			(start -0.12065 0.3048)
			(end -0.67945 0.3048)
			(stroke
				(width 0.1)
				(type default)
			)
			(layer "F.Fab")
		)
		(fp_line
			(start -0.67945 0.3048)
			(end -0.67945 -0.305054)
			(stroke
				(width 0.1)
				(type default)
			)
			(layer "F.Fab")
		)
		(pad "1" smd circle
			(at -0.40005 0 90)
			(size 0 0)
			(layers "F.Cu" "F.Mask" "F.Paste")
			(net "P12V_AUX")
		)
		(pad "2" smd circle
			(at 0.40005 0 90)
			(size 0 0)
			(layers "F.Cu" "F.Mask" "F.Paste")
			(net "P3V3_OCP_2_EN_G")
		)
	)
	(footprint ""
		(layer "F.Cu")
		(at 28.534106 19.444716 -90)
		(property "Reference" "LBL_1"
			(at 0 0 270)
			(layer "F.SilkS")
			(hide yes)
			(effects
				(font
					(size 1.27 1.27)
				)
			)
		)
		(property "Value" ""
			(at 0 0 270)
			(layer "F.Fab")
			(effects
				(font
					(size 1.27 1.27)
				)
			)
		)
		(duplicate_pad_numbers_are_jumpers no)
		(pad "1" smd circle
			(at 0 0 270)
			(size 0.762 0.762)
			(layers "F.Cu" "F.Mask" "F.Paste")
			(net "Net_10817")
		)
	)
)
